(kicad_pcb
	(version 20260206)
	(generator "pcbnew")
	(generator_version "10.0")
	(general
		(thickness 1.6)
		(legacy_teardrops no)
	)
	(paper "A4")
	(title_block
		(title "Bryce Canyon_SCC_16316-1_OCP.brd")
		(comment 1 "Bryce Canyon / footprints 162-168 of 1561")
	)
	(layers
		(0 "F.Cu" signal "TOP")
		(4 "In1.Cu" signal "L2GND")
		(6 "In2.Cu" signal "L3")
		(8 "In3.Cu" signal "L4VCC")
		(10 "In4.Cu" signal "L5VCC")
		(12 "In5.Cu" signal "L6")
		(14 "In6.Cu" signal "L7GND")
		(2 "B.Cu" signal "BOTTOM")
		(9 "F.Adhes" user "F.Adhesive")
		(11 "B.Adhes" user "B.Adhesive")
		(13 "F.Paste" user "Package Geometry/Pastemask Top")
		(15 "B.Paste" user "Package Geometry/Pastemask Bottom")
		(5 "F.SilkS" user "Ref Des/Silkscreen Top")
		(7 "B.SilkS" user "Ref Des/Silkscreen Bottom")
		(1 "F.Mask" user "Board Geometry/Soldermask Top")
		(3 "B.Mask" user "Board Geometry/Soldermask Bottom")
		(17 "Dwgs.User" user "User.Drawings")
		(19 "Cmts.User" user "User.Comments")
		(21 "Eco1.User" user "User.Eco1")
		(23 "Eco2.User" user "User.Eco2")
		(25 "Edge.Cuts" user "Board Geometry/Outline")
		(27 "Margin" user)
		(31 "F.CrtYd" user "Package Geometry/Place Bound Top")
		(29 "B.CrtYd" user "Package Geometry/Place Bound Bottom")
		(35 "F.Fab" user "Ref Des/Assembly Top")
		(33 "B.Fab" user "Ref Des/Assembly Bottom")
	)
	(footprint ""
		(layer "F.Cu")
		(at 135.382 -113.157 -90)
		(property "Reference" "TC5"
			(at 0 0 270)
			(layer "F.SilkS")
			(hide yes)
			(effects
				(font
					(size 1.27 1.27)
				)
			)
		)
		(property "Value" "ST150U6D3VDM-28-GP"
			(at 0 -9.6012 270)
			(unlocked yes)
			(layer "F.Fab")
			(hide yes)
			(effects
				(font
					(size 1.016 1.016)
					(thickness 0.1524)
				)
			)
		)
		(property "Device Type" "CT7343H83"
			(at 0 -11.1252 270)
			(unlocked yes)
			(layer "F.Fab")
			(hide yes)
			(effects
				(font
					(size 1.016 1.016)
					(thickness 0.1524)
				)
			)
		)
		(duplicate_pad_numbers_are_jumpers no)
		(fp_line
			(start -2.286 4.8768)
			(end -2.286 2.032)
			(stroke
				(width 0.1524)
				(type default)
			)
			(layer "F.SilkS")
		)
		(fp_line
			(start 2.286 4.8768)
			(end -2.286 4.8768)
			(stroke
				(width 0.1524)
				(type default)
			)
			(layer "F.SilkS")
		)
		(fp_line
			(start 2.286 2.032)
			(end 2.286 4.8768)
			(stroke
				(width 0.1524)
				(type default)
			)
			(layer "F.SilkS")
		)
		(fp_line
			(start 2.286 -2.032)
			(end 2.286 -4.8768)
			(stroke
				(width 0.1524)
				(type default)
			)
			(layer "F.SilkS")
		)
		(fp_line
			(start 2.1082 -4.699)
			(end -2.1082 -4.699)
			(stroke
				(width 0.508)
				(type default)
			)
			(layer "F.SilkS")
		)
		(fp_line
			(start -2.286 -4.8768)
			(end -2.286 -2.032)
			(stroke
				(width 0.1524)
				(type default)
			)
			(layer "F.SilkS")
		)
		(fp_line
			(start 2.286 -4.8768)
			(end -2.286 -4.8768)
			(stroke
				(width 0.1524)
				(type default)
			)
			(layer "F.SilkS")
		)
		(fp_rect
			(start -2.1463 3.6449)
			(end 2.1463 -3.6449)
			(stroke
				(width 0)
				(type default)
			)
			(fill no)
			(layer "F.CrtYd")
		)
		(fp_poly
			(pts
				(xy -2.54 4.953) (xy -2.54 4.2926) (xy -3.81 4.2926) (xy -3.81 -4.2926) (xy -2.54 -4.2926) (xy -2.54 -4.953)
				(xy 2.54 -4.953) (xy 2.54 -4.2926) (xy 3.81 -4.2926) (xy 3.81 -1.6256) (xy 2.1463 -1.6256) (xy 2.1463 -3.6449)
				(xy -2.1463 -3.6449) (xy -2.1463 3.6449) (xy 2.1463 3.6449) (xy 2.1463 -1.6129) (xy 3.81 -1.6129)
				(xy 3.81 4.2926) (xy 2.54 4.2926) (xy 2.54 4.953)
			)
			(stroke
				(width 0)
				(type default)
			)
			(fill no)
			(layer "F.CrtYd")
		)
		(fp_rect
			(start -2.54 4.953)
			(end 2.54 -4.953)
			(stroke
				(width 0)
				(type default)
			)
			(fill no)
			(layer "F.Fab")
		)
		(fp_rect
			(start -3.81 4.2926)
			(end -2.54 -4.2926)
			(stroke
				(width 0)
				(type default)
			)
			(fill no)
			(layer "F.Fab")
		)
		(fp_rect
			(start 2.54 4.2926)
			(end 3.81 -4.2926)
			(stroke
				(width 0)
				(type default)
			)
			(fill no)
			(layer "F.Fab")
		)
		(pad "1" smd rect
			(at 0 -3.1496 270)
			(size 2.413 2.286)
			(layers "F.Cu" "F.Mask" "F.Paste")
			(net "P1V5_E_OUT")
		)
		(pad "2" smd rect
			(at 0 3.1496 270)
			(size 2.413 2.286)
			(layers "F.Cu" "F.Mask" "F.Paste")
			(net "GND")
		)
		(zone
			(layer "F.Cu")
			(hatch none 0.5)
			(connect_pads
				(clearance 0)
			)
			(min_thickness 0.25)
			(keepout
				(tracks allowed)
				(vias not_allowed)
				(pads allowed)
				(copperpour not_allowed)
				(footprints allowed)
			)
			(placement
				(enabled no)
				(sheetname "")
			)
			(fill
				(thermal_gap 0.5)
				(thermal_bridge_width 0.5)
				(island_removal_mode 0)
			)
			(polygon
				(pts
					(xy 130.7846 -114.6683) (xy 130.7846 -111.6457) (xy 133.6802 -111.6457) (xy 134.0104 -111.6457)
					(xy 134.0104 -114.6683) (xy 133.6802 -114.6683)
				)
			)
		)
		(zone
			(layer "F.Cu")
			(hatch none 0.5)
			(connect_pads
				(clearance 0)
			)
			(min_thickness 0.25)
			(keepout
				(tracks allowed)
				(vias not_allowed)
				(pads allowed)
				(copperpour not_allowed)
				(footprints allowed)
			)
			(placement
				(enabled no)
				(sheetname "")
			)
			(fill
				(thermal_gap 0.5)
				(thermal_bridge_width 0.5)
				(island_removal_mode 0)
			)
			(polygon
				(pts
					(xy 137.0711 -111.6457) (xy 139.9794 -111.6457) (xy 139.9794 -114.6683) (xy 137.0838 -114.6683)
					(xy 136.7536 -114.6683) (xy 136.7536 -111.6457)
				)
			)
		)
	)
	(footprint ""
		(layer "F.Cu")
		(at 182.8419 -110.16488)
		(property "Reference" "Q12"
			(at 0 0 0)
			(layer "F.SilkS")
			(hide yes)
			(effects
				(font
					(size 1.27 1.27)
				)
			)
		)
		(property "Value" "2N7002K-1-GP"
			(at 0.127 -8.9662 0)
			(unlocked yes)
			(layer "F.Fab")
			(hide yes)
			(effects
				(font
					(size 1.016 1.016)
					(thickness 0.1524)
				)
			)
		)
		(property "Device Type" "SOT23DGS2D4H44"
			(at 0.127 -10.4902 0)
			(unlocked yes)
			(layer "F.Fab")
			(hide yes)
			(effects
				(font
					(size 1.016 1.016)
					(thickness 0.1524)
				)
			)
		)
		(duplicate_pad_numbers_are_jumpers no)
		(fp_line
			(start -1.651 -1.778)
			(end -1.651 1.778)
			(stroke
				(width 0.1524)
				(type default)
			)
			(layer "F.SilkS")
		)
		(fp_line
			(start -1.651 1.778)
			(end 1.651 1.778)
			(stroke
				(width 0.1524)
				(type default)
			)
			(layer "F.SilkS")
		)
		(fp_line
			(start 1.651 -1.778)
			(end -1.651 -1.778)
			(stroke
				(width 0.1524)
				(type default)
			)
			(layer "F.SilkS")
		)
		(fp_line
			(start 1.651 1.778)
			(end 1.651 -1.778)
			(stroke
				(width 0.1524)
				(type default)
			)
			(layer "F.SilkS")
		)
		(fp_poly
			(pts
				(xy -1.778 1.8796) (xy -1.778 -1.8796) (xy 1.778 -1.8796) (xy 1.778 1.8796)
			)
			(stroke
				(width 0)
				(type default)
			)
			(fill no)
			(layer "F.CrtYd")
		)
		(fp_poly
			(pts
				(xy -1.778 1.8796) (xy -1.778 -1.8796) (xy 1.778 -1.8796) (xy 1.778 1.8796)
			)
			(stroke
				(width 0)
				(type default)
			)
			(fill no)
			(layer "F.Fab")
		)
		(pad "D" smd custom
			(at 0 -0.9525)
			(size 0.1905 0.1905)
			(layers "F.Cu" "F.Mask" "F.Paste")
			(net "P1V8_C_PG_R_1")
			(options
				(clearance outline)
				(anchor circle)
			)
			(primitives
				(gr_poly
					(pts
						(arc
							(start -0.1778 0.5715)
							(mid -0.321484 0.511984)
							(end -0.381 0.3683)
						)
						(arc
							(start -0.381 -0.3683)
							(mid -0.321484 -0.511984)
							(end -0.1778 -0.5715)
						)
						(arc
							(start 0.1778 -0.5715)
							(mid 0.321484 -0.511984)
							(end 0.381 -0.3683)
						)
						(arc
							(start 0.381 0.3683)
							(mid 0.321484 0.511984)
							(end 0.1778 0.5715)
						)
					)
					(width 0)
					(fill yes)
				)
			)
		)
		(pad "G" smd custom
			(at -0.98425 0.9525)
			(size 0.1905 0.1905)
			(layers "F.Cu" "F.Mask" "F.Paste")
			(net "P12V_STBY_Q12_G")
			(options
				(clearance outline)
				(anchor circle)
			)
			(primitives
				(gr_poly
					(pts
						(arc
							(start -0.1778 0.5715)
							(mid -0.321484 0.511984)
							(end -0.381 0.3683)
						)
						(arc
							(start -0.381 -0.3683)
							(mid -0.321484 -0.511984)
							(end -0.1778 -0.5715)
						)
						(arc
							(start 0.1778 -0.5715)
							(mid 0.321484 -0.511984)
							(end 0.381 -0.3683)
						)
						(arc
							(start 0.381 0.3683)
							(mid 0.321484 0.511984)
							(end 0.1778 0.5715)
						)
					)
					(width 0)
					(fill yes)
				)
			)
		)
		(pad "S" smd custom
			(at 0.98425 0.9525)
			(size 0.1905 0.1905)
			(layers "F.Cu" "F.Mask" "F.Paste")
			(net "GND")
			(options
				(clearance outline)
				(anchor circle)
			)
			(primitives
				(gr_poly
					(pts
						(arc
							(start -0.1778 0.5715)
							(mid -0.321484 0.511984)
							(end -0.381 0.3683)
						)
						(arc
							(start -0.381 -0.3683)
							(mid -0.321484 -0.511984)
							(end -0.1778 -0.5715)
						)
						(arc
							(start 0.1778 -0.5715)
							(mid 0.321484 -0.511984)
							(end 0.381 -0.3683)
						)
						(arc
							(start 0.381 0.3683)
							(mid 0.321484 0.511984)
							(end 0.1778 0.5715)
						)
					)
					(width 0)
					(fill yes)
				)
			)
		)
	)
	(footprint ""
		(layer "F.Cu")
		(at 167.11168 -56.27624)
		(property "Reference" "TP121"
			(at 0 0 0)
			(layer "F.SilkS")
			(hide yes)
			(effects
				(font
					(size 1.27 1.27)
				)
			)
		)
		(property "Value" "TPAD28-2-GP"
			(at -0.0127 -1.6637 0)
			(unlocked yes)
			(layer "F.Fab")
			(hide yes)
			(effects
				(font
					(size 1.016 1.016)
					(thickness 0.1524)
				)
			)
		)
		(property "Device Type" "TPAD28"
			(at -0.0127 -3.1877 0)
			(unlocked yes)
			(layer "F.Fab")
			(hide yes)
			(effects
				(font
					(size 1.016 1.016)
					(thickness 0.1524)
				)
			)
		)
		(duplicate_pad_numbers_are_jumpers no)
		(fp_poly
			(pts
				(arc
					(start 0.3556 0)
					(mid -0.3556 0)
					(end 0.3556 0)
				)
			)
			(stroke
				(width 0)
				(type default)
			)
			(fill no)
			(layer "F.CrtYd")
		)
		(fp_poly
			(pts
				(arc
					(start 0.6096 0)
					(mid -0.6096 0)
					(end 0.6096 0)
				)
			)
			(stroke
				(width 0)
				(type default)
			)
			(fill no)
			(layer "F.Fab")
		)
		(pad "1" smd circle
			(at 0 0)
			(size 0.7112 0.7112)
			(layers "F.Cu" "F.Mask" "F.Paste")
			(net "ICE0_TDI")
		)
	)
	(footprint ""
		(layer "F.Cu")
		(at 70.104 -7.366 90)
		(property "Reference" "R89"
			(at 0 0 90)
			(layer "F.SilkS")
			(hide yes)
			(effects
				(font
					(size 1.27 1.27)
				)
			)
		)
		(property "Value" "0R2J-2-GP"
			(at 0.064008 -3.993896 90)
			(unlocked yes)
			(layer "F.Fab")
			(hide yes)
			(effects
				(font
					(size 1.016 1.016)
					(thickness 0.1524)
				)
			)
		)
		(property "Device Type" "R402H16"
			(at 0.064008 -5.517896 90)
			(unlocked yes)
			(layer "F.Fab")
			(hide yes)
			(effects
				(font
					(size 1.016 1.016)
					(thickness 0.1524)
				)
			)
		)
		(duplicate_pad_numbers_are_jumpers no)
		(fp_line
			(start 0.508 -0.9398)
			(end -0.508 -0.9398)
			(stroke
				(width 0.1524)
				(type default)
			)
			(layer "F.SilkS")
		)
		(fp_line
			(start -0.508 -0.9398)
			(end -0.508 0.9398)
			(stroke
				(width 0.1524)
				(type default)
			)
			(layer "F.SilkS")
		)
		(fp_rect
			(start -0.508 0.9398)
			(end 0.508 -0.9398)
			(stroke
				(width 0)
				(type default)
			)
			(fill no)
			(layer "F.CrtYd")
		)
		(fp_rect
			(start -0.508 0.9398)
			(end 0.508 -0.9398)
			(stroke
				(width 0)
				(type default)
			)
			(fill no)
			(layer "F.Fab")
		)
		(pad "1" smd custom
			(at 0 -0.4445 90)
			(size 0.1397 0.1397)
			(layers "F.Cu" "F.Mask" "F.Paste")
			(net "GND")
			(options
				(clearance outline)
				(anchor circle)
			)
			(primitives
				(gr_poly
					(pts
						(arc
							(start -0.1778 -0.2794)
							(mid -0.249642 -0.249642)
							(end -0.2794 -0.1778)
						)
						(arc
							(start -0.2794 0.1778)
							(mid -0.249642 0.249642)
							(end -0.1778 0.2794)
						)
						(arc
							(start 0.1778 0.2794)
							(mid 0.249642 0.249642)
							(end 0.2794 0.1778)
						)
						(arc
							(start 0.2794 -0.1778)
							(mid 0.249642 -0.249642)
							(end 0.1778 -0.2794)
						)
					)
					(width 0)
					(fill yes)
				)
			)
		)
		(pad "2" smd custom
			(at 0 0.4445 90)
			(size 0.1397 0.1397)
			(layers "F.Cu" "F.Mask" "F.Paste")
			(net "SCC_TYPE_0")
			(options
				(clearance outline)
				(anchor circle)
			)
			(primitives
				(gr_poly
					(pts
						(arc
							(start -0.1778 -0.2794)
							(mid -0.249642 -0.249642)
							(end -0.2794 -0.1778)
						)
						(arc
							(start -0.2794 0.1778)
							(mid -0.249642 0.249642)
							(end -0.1778 0.2794)
						)
						(arc
							(start 0.1778 0.2794)
							(mid 0.249642 0.249642)
							(end 0.2794 0.1778)
						)
						(arc
							(start 0.2794 -0.1778)
							(mid 0.249642 -0.249642)
							(end 0.1778 -0.2794)
						)
					)
					(width 0)
					(fill yes)
				)
			)
		)
	)
	(footprint ""
		(layer "F.Cu")
		(at 188.8744 -56.5658 180)
		(property "Reference" "R226"
			(at 0 0 180)
			(layer "F.SilkS")
			(hide yes)
			(effects
				(font
					(size 1.27 1.27)
				)
			)
		)
		(property "Value" "10KR2F-2-GP"
			(at 0.064008 -3.993896 180)
			(unlocked yes)
			(layer "F.Fab")
			(hide yes)
			(effects
				(font
					(size 1.016 1.016)
					(thickness 0.1524)
				)
			)
		)
		(property "Device Type" "R402H16"
			(at 0.064008 -5.517896 180)
			(unlocked yes)
			(layer "F.Fab")
			(hide yes)
			(effects
				(font
					(size 1.016 1.016)
					(thickness 0.1524)
				)
			)
		)
		(duplicate_pad_numbers_are_jumpers no)
		(fp_line
			(start 0.508 -0.9398)
			(end -0.508 -0.9398)
			(stroke
				(width 0.1524)
				(type default)
			)
			(layer "F.SilkS")
		)
		(fp_line
			(start -0.508 -0.9398)
			(end -0.508 0.9398)
			(stroke
				(width 0.1524)
				(type default)
			)
			(layer "F.SilkS")
		)
		(fp_rect
			(start -0.508 0.9398)
			(end 0.508 -0.9398)
			(stroke
				(width 0)
				(type default)
			)
			(fill no)
			(layer "F.CrtYd")
		)
		(fp_rect
			(start -0.508 0.9398)
			(end 0.508 -0.9398)
			(stroke
				(width 0)
				(type default)
			)
			(fill no)
			(layer "F.Fab")
		)
		(pad "1" smd custom
			(at 0 -0.4445 180)
			(size 0.1397 0.1397)
			(layers "F.Cu" "F.Mask" "F.Paste")
			(net "XM_ADDR_6")
			(options
				(clearance outline)
				(anchor circle)
			)
			(primitives
				(gr_poly
					(pts
						(arc
							(start -0.1778 -0.2794)
							(mid -0.249642 -0.249642)
							(end -0.2794 -0.1778)
						)
						(arc
							(start -0.2794 0.1778)
							(mid -0.249642 0.249642)
							(end -0.1778 0.2794)
						)
						(arc
							(start 0.1778 0.2794)
							(mid 0.249642 0.249642)
							(end 0.2794 0.1778)
						)
						(arc
							(start 0.2794 -0.1778)
							(mid 0.249642 -0.249642)
							(end 0.1778 -0.2794)
						)
					)
					(width 0)
					(fill yes)
				)
			)
		)
		(pad "2" smd custom
			(at 0 0.4445 180)
			(size 0.1397 0.1397)
			(layers "F.Cu" "F.Mask" "F.Paste")
			(net "GND")
			(options
				(clearance outline)
				(anchor circle)
			)
			(primitives
				(gr_poly
					(pts
						(arc
							(start -0.1778 -0.2794)
							(mid -0.249642 -0.249642)
							(end -0.2794 -0.1778)
						)
						(arc
							(start -0.2794 0.1778)
							(mid -0.249642 0.249642)
							(end -0.1778 0.2794)
						)
						(arc
							(start 0.1778 0.2794)
							(mid 0.249642 0.249642)
							(end 0.2794 0.1778)
						)
						(arc
							(start 0.2794 -0.1778)
							(mid 0.249642 -0.249642)
							(end 0.1778 -0.2794)
						)
					)
					(width 0)
					(fill yes)
				)
			)
		)
	)
	(footprint ""
		(layer "F.Cu")
		(at 15.1892 -47.2186 180)
		(property "Reference" "C646"
			(at 0 0 180)
			(layer "F.SilkS")
			(hide yes)
			(effects
				(font
					(size 1.27 1.27)
				)
			)
		)
		(property "Value" "SC1U25V3KX-GP"
			(at 0 -2.8194 180)
			(unlocked yes)
			(layer "F.Fab")
			(hide yes)
			(effects
				(font
					(size 1.016 1.016)
					(thickness 0.1524)
				)
			)
		)
		(property "Device Type" "C603H36"
			(at 0 -4.3434 180)
			(unlocked yes)
			(layer "F.Fab")
			(hide yes)
			(effects
				(font
					(size 1.016 1.016)
					(thickness 0.1524)
				)
			)
		)
		(duplicate_pad_numbers_are_jumpers no)
		(fp_line
			(start 0.508 0)
			(end -0.508 0)
			(stroke
				(width 0.2032)
				(type default)
			)
			(layer "F.SilkS")
		)
		(fp_rect
			(start -0.5842 1.3335)
			(end 0.5842 -1.3335)
			(stroke
				(width 0)
				(type default)
			)
			(fill no)
			(layer "F.CrtYd")
		)
		(fp_rect
			(start -0.5842 1.3335)
			(end 0.5842 -1.3335)
			(stroke
				(width 0)
				(type default)
			)
			(fill no)
			(layer "F.Fab")
		)
		(pad "1" smd custom
			(at 0 -0.762 180)
			(size 0.2159 0.2159)
			(layers "F.Cu" "F.Mask" "F.Paste")
			(net "AGND_CURRENT_MON")
			(options
				(clearance outline)
				(anchor circle)
			)
			(primitives
				(gr_poly
					(pts
						(arc
							(start -0.3302 -0.4318)
							(mid -0.402042 -0.402042)
							(end -0.4318 -0.3302)
						)
						(arc
							(start -0.4318 0.3302)
							(mid -0.402042 0.402042)
							(end -0.3302 0.4318)
						)
						(arc
							(start 0.3302 0.4318)
							(mid 0.402042 0.402042)
							(end 0.4318 0.3302)
						)
						(arc
							(start 0.4318 -0.3302)
							(mid 0.402042 -0.402042)
							(end 0.3302 -0.4318)
						)
					)
					(width 0)
					(fill yes)
				)
			)
		)
		(pad "2" smd custom
			(at 0 0.762 180)
			(size 0.2159 0.2159)
			(layers "F.Cu" "F.Mask" "F.Paste")
			(net "MB0_VCC")
			(options
				(clearance outline)
				(anchor circle)
			)
			(primitives
				(gr_poly
					(pts
						(arc
							(start -0.3302 -0.4318)
							(mid -0.402042 -0.402042)
							(end -0.4318 -0.3302)
						)
						(arc
							(start -0.4318 0.3302)
							(mid -0.402042 0.402042)
							(end -0.3302 0.4318)
						)
						(arc
							(start 0.3302 0.4318)
							(mid 0.402042 0.402042)
							(end 0.4318 0.3302)
						)
						(arc
							(start 0.4318 -0.3302)
							(mid 0.402042 -0.402042)
							(end 0.3302 -0.4318)
						)
					)
					(width 0)
					(fill yes)
				)
			)
		)
	)
	(footprint ""
		(layer "F.Cu")
		(at 159.85998 -116.41582 180)
		(property "Reference" "R316"
			(at 0 0 180)
			(layer "F.SilkS")
			(hide yes)
			(effects
				(font
					(size 1.27 1.27)
				)
			)
		)
		(property "Value" "866KR2F-GP"
			(at 0.064008 -3.993896 180)
			(unlocked yes)
			(layer "F.Fab")
			(hide yes)
			(effects
				(font
					(size 1.016 1.016)
					(thickness 0.1524)
				)
			)
		)
		(property "Device Type" "R402H16"
			(at 0.064008 -5.517896 180)
			(unlocked yes)
			(layer "F.Fab")
			(hide yes)
			(effects
				(font
					(size 1.016 1.016)
					(thickness 0.1524)
				)
			)
		)
		(duplicate_pad_numbers_are_jumpers no)
		(fp_line
			(start 0.508 -0.9398)
			(end -0.508 -0.9398)
			(stroke
				(width 0.1524)
				(type default)
			)
			(layer "F.SilkS")
		)
		(fp_line
			(start -0.508 -0.9398)
			(end -0.508 0.9398)
			(stroke
				(width 0.1524)
				(type default)
			)
			(layer "F.SilkS")
		)
		(fp_rect
			(start -0.508 0.9398)
			(end 0.508 -0.9398)
			(stroke
				(width 0)
				(type default)
			)
			(fill no)
			(layer "F.CrtYd")
		)
		(fp_rect
			(start -0.508 0.9398)
			(end 0.508 -0.9398)
			(stroke
				(width 0)
				(type default)
			)
			(fill no)
			(layer "F.Fab")
		)
		(pad "1" smd custom
			(at 0 -0.4445 180)
			(size 0.1397 0.1397)
			(layers "F.Cu" "F.Mask" "F.Paste")
			(net "P1V5_E_VREG")
			(options
				(clearance outline)
				(anchor circle)
			)
			(primitives
				(gr_poly
					(pts
						(arc
							(start -0.1778 -0.2794)
							(mid -0.249642 -0.249642)
							(end -0.2794 -0.1778)
						)
						(arc
							(start -0.2794 0.1778)
							(mid -0.249642 0.249642)
							(end -0.1778 0.2794)
						)
						(arc
							(start 0.1778 0.2794)
							(mid 0.249642 0.249642)
							(end 0.2794 0.1778)
						)
						(arc
							(start 0.2794 -0.1778)
							(mid 0.249642 -0.249642)
							(end 0.1778 -0.2794)
						)
					)
					(width 0)
					(fill yes)
				)
			)
		)
		(pad "2" smd custom
			(at 0 0.4445 180)
			(size 0.1397 0.1397)
			(layers "F.Cu" "F.Mask" "F.Paste")
			(net "P1V5_E_RF")
			(options
				(clearance outline)
				(anchor circle)
			)
			(primitives
				(gr_poly
					(pts
						(arc
							(start -0.1778 -0.2794)
							(mid -0.249642 -0.249642)
							(end -0.2794 -0.1778)
						)
						(arc
							(start -0.2794 0.1778)
							(mid -0.249642 0.249642)
							(end -0.1778 0.2794)
						)
						(arc
							(start 0.1778 0.2794)
							(mid 0.249642 0.249642)
							(end 0.2794 0.1778)
						)
						(arc
							(start 0.2794 -0.1778)
							(mid 0.249642 -0.249642)
							(end 0.1778 -0.2794)
						)
					)
					(width 0)
					(fill yes)
				)
			)
		)
	)
)
